(kicad_pcb
	(version 20260206)
	(generator "pcbnew")
	(generator_version "10.0")
	(general
		(thickness 1.6)
		(legacy_teardrops no)
	)
	(paper "A4")
	(title_block
		(title "04192023_DAF0TMB3IC0_F0TG_MB_C_brd_V02_OCP.brd")
		(comment 1 "Grand Teton / footprints 1864-1868 of 8354")
	)
	(layers
		(0 "F.Cu" signal "TOP")
		(4 "In1.Cu" signal "GND")
		(6 "In2.Cu" signal "IN1")
		(8 "In3.Cu" signal "GND1")
		(10 "In4.Cu" signal "IN2")
		(12 "In5.Cu" signal "GND2")
		(14 "In6.Cu" signal "IN3")
		(16 "In7.Cu" signal "GND3")
		(18 "In8.Cu" signal "VCC")
		(20 "In9.Cu" signal "VCC1")
		(22 "In10.Cu" signal "GND4")
		(24 "In11.Cu" signal "IN4")
		(26 "In12.Cu" signal "GND5")
		(28 "In13.Cu" signal "IN5")
		(30 "In14.Cu" signal "GND6")
		(32 "In15.Cu" signal "IN6")
		(34 "In16.Cu" signal "GND7")
		(2 "B.Cu" signal "BOTTOM")
		(9 "F.Adhes" user "F.Adhesive")
		(11 "B.Adhes" user "B.Adhesive")
		(13 "F.Paste" user "Package Geometry/Pastemask Top")
		(15 "B.Paste" user "Package Geometry/Pastemask Bottom")
		(5 "F.SilkS" user "Ref Des/Silkscreen Top")
		(7 "B.SilkS" user "Ref Des/Silkscreen Bottom")
		(1 "F.Mask" user "Board Geometry/Soldermask Top")
		(3 "B.Mask" user "Board Geometry/Soldermask Bottom")
		(17 "Dwgs.User" user "User.Drawings")
		(19 "Cmts.User" user "User.Comments")
		(21 "Eco1.User" user "User.Eco1")
		(23 "Eco2.User" user "User.Eco2")
		(25 "Edge.Cuts" user "Board Geometry/Outline")
		(27 "Margin" user)
		(31 "F.CrtYd" user "Package Geometry/Place Bound Top")
		(29 "B.CrtYd" user "Package Geometry/Place Bound Bottom")
		(35 "F.Fab" user "Ref Des/Assembly Top")
		(33 "B.Fab" user "Ref Des/Assembly Bottom")
	)
	(footprint ""
		(layer "F.Cu")
		(at 301.221902 -20.04695 -90)
		(property "Reference" "Q8"
			(at 1.510792 -2.157222 90)
			(unlocked yes)
			(layer "F.SilkS")
			(effects
				(font
					(size 0.7874 0.5842)
					(thickness 0.1524)
				)
				(justify left)
			)
		)
		(property "Value" ""
			(at 0 0 270)
			(layer "F.Fab")
			(effects
				(font
					(size 1.27 1.27)
				)
			)
		)
		(duplicate_pad_numbers_are_jumpers no)
		(fp_line
			(start -1.332738 1.100074)
			(end -1.332738 -1.100074)
			(stroke
				(width 0.1524)
				(type default)
			)
			(layer "F.SilkS")
		)
		(fp_line
			(start 1.332738 1.100074)
			(end -1.332738 1.100074)
			(stroke
				(width 0.1524)
				(type default)
			)
			(layer "F.SilkS")
		)
		(fp_line
			(start 0 -0.541274)
			(end 0.4826 -1.100074)
			(stroke
				(width 0.1524)
				(type default)
			)
			(layer "F.SilkS")
		)
		(fp_line
			(start -1.332738 -1.100074)
			(end -0.4826 -1.100074)
			(stroke
				(width 0.1524)
				(type default)
			)
			(layer "F.SilkS")
		)
		(fp_line
			(start -0.4826 -1.100074)
			(end 0 -0.541274)
			(stroke
				(width 0.1524)
				(type default)
			)
			(layer "F.SilkS")
		)
		(fp_line
			(start 0.4826 -1.100074)
			(end 1.332738 -1.100074)
			(stroke
				(width 0.1524)
				(type default)
			)
			(layer "F.SilkS")
		)
		(fp_line
			(start 1.332738 -1.100074)
			(end 1.332738 1.100074)
			(stroke
				(width 0.1524)
				(type default)
			)
			(layer "F.SilkS")
		)
		(fp_poly
			(pts
				(xy -0.983742 -1.228852) (xy -1.33477 -1.930908) (xy -0.632714 -1.930908)
			)
			(stroke
				(width 0)
				(type default)
			)
			(fill yes)
			(layer "F.SilkS")
		)
		(fp_line
			(start -0.674878 1.100074)
			(end -0.674878 -1.100074)
			(stroke
				(width 0.1)
				(type default)
			)
			(layer "F.Fab")
		)
		(fp_line
			(start 0.674878 1.100074)
			(end -0.674878 1.100074)
			(stroke
				(width 0.1)
				(type default)
			)
			(layer "F.Fab")
		)
		(fp_line
			(start -0.674878 -1.100074)
			(end 0.674878 -1.100074)
			(stroke
				(width 0.1)
				(type default)
			)
			(layer "F.Fab")
		)
		(fp_line
			(start 0.674878 -1.100074)
			(end 0.674878 1.100074)
			(stroke
				(width 0.1)
				(type default)
			)
			(layer "F.Fab")
		)
		(fp_poly
			(pts
				(xy -2.2352 -0.298958) (xy -2.2352 -1.001014) (xy -1.533144 -0.649986)
			)
			(stroke
				(width 0)
				(type default)
			)
			(fill yes)
			(layer "F.Fab")
		)
		(pad "1" smd rect
			(at -0.94996 -0.649986)
			(size 0.4318 0.508)
			(layers "F.Cu" "F.Mask" "F.Paste")
			(net "GND")
		)
		(pad "2" smd rect
			(at -0.94996 0)
			(size 0.4318 0.508)
			(layers "F.Cu" "F.Mask" "F.Paste")
			(net "CLR_CMOS")
		)
		(pad "3" smd rect
			(at -0.94996 0.649986)
			(size 0.4318 0.508)
			(layers "F.Cu" "F.Mask" "F.Paste")
			(net "BAT_LDO_EN")
		)
		(pad "4" smd rect
			(at 0.94996 0.649986)
			(size 0.4318 0.508)
			(layers "F.Cu" "F.Mask" "F.Paste")
			(net "GND")
		)
		(pad "5" smd rect
			(at 0.94996 0)
			(size 0.4318 0.508)
			(layers "F.Cu" "F.Mask" "F.Paste")
			(net "CLR_CMOS")
		)
		(pad "6" smd rect
			(at 0.94996 -0.649986)
			(size 0.4318 0.508)
			(layers "F.Cu" "F.Mask" "F.Paste")
			(net "CLR_CMOS_N")
		)
	)
	(footprint ""
		(layer "F.Cu")
		(at 21.176996 -97.083626 180)
		(property "Reference" "R3663"
			(at 0 0 180)
			(layer "F.SilkS")
			(hide yes)
			(effects
				(font
					(size 1.27 1.27)
				)
			)
		)
		(property "Value" ""
			(at 0 0 180)
			(layer "F.Fab")
			(effects
				(font
					(size 1.27 1.27)
				)
			)
		)
		(duplicate_pad_numbers_are_jumpers no)
		(fp_line
			(start 0.7874 0.4064)
			(end -0.7874 0.4064)
			(stroke
				(width 0.1524)
				(type default)
			)
			(layer "F.SilkS")
		)
		(fp_line
			(start 0.7874 -0.4064)
			(end 0.7874 0.4064)
			(stroke
				(width 0.1524)
				(type default)
			)
			(layer "F.SilkS")
		)
		(fp_line
			(start -0.7874 0.4064)
			(end -0.7874 -0.4064)
			(stroke
				(width 0.1524)
				(type default)
			)
			(layer "F.SilkS")
		)
		(fp_line
			(start -0.7874 -0.4064)
			(end 0.7874 -0.4064)
			(stroke
				(width 0.1524)
				(type default)
			)
			(layer "F.SilkS")
		)
		(fp_line
			(start 0.67945 0.3048)
			(end 0.120396 0.3048)
			(stroke
				(width 0.1)
				(type default)
			)
			(layer "F.Fab")
		)
		(fp_line
			(start 0.67945 -0.3048)
			(end 0.67945 0.3048)
			(stroke
				(width 0.1)
				(type default)
			)
			(layer "F.Fab")
		)
		(fp_line
			(start 0.12065 -0.2794)
			(end 0.12065 -0.3048)
			(stroke
				(width 0.1)
				(type default)
			)
			(layer "F.Fab")
		)
		(fp_line
			(start 0.12065 -0.3048)
			(end 0.67945 -0.3048)
			(stroke
				(width 0.1)
				(type default)
			)
			(layer "F.Fab")
		)
		(fp_line
			(start 0.120396 0.3048)
			(end 0.120396 0.2794)
			(stroke
				(width 0.1)
				(type default)
			)
			(layer "F.Fab")
		)
		(fp_line
			(start 0.120396 0.2794)
			(end -0.12065 0.2794)
			(stroke
				(width 0.1)
				(type default)
			)
			(layer "F.Fab")
		)
		(fp_line
			(start -0.12065 0.3048)
			(end -0.67945 0.3048)
			(stroke
				(width 0.1)
				(type default)
			)
			(layer "F.Fab")
		)
		(fp_line
			(start -0.12065 0.2794)
			(end -0.12065 0.3048)
			(stroke
				(width 0.1)
				(type default)
			)
			(layer "F.Fab")
		)
		(fp_line
			(start -0.12065 -0.2794)
			(end 0.12065 -0.2794)
			(stroke
				(width 0.1)
				(type default)
			)
			(layer "F.Fab")
		)
		(fp_line
			(start -0.12065 -0.305054)
			(end -0.12065 -0.2794)
			(stroke
				(width 0.1)
				(type default)
			)
			(layer "F.Fab")
		)
		(fp_line
			(start -0.67945 0.3048)
			(end -0.67945 -0.305054)
			(stroke
				(width 0.1)
				(type default)
			)
			(layer "F.Fab")
		)
		(fp_line
			(start -0.67945 -0.305054)
			(end -0.12065 -0.305054)
			(stroke
				(width 0.1)
				(type default)
			)
			(layer "F.Fab")
		)
		(pad "1" smd circle
			(at -0.40005 0 180)
			(size 0 0)
			(layers "F.Cu" "F.Mask" "F.Paste")
			(net "P3V3_AUX")
		)
		(pad "2" smd circle
			(at 0.40005 0 180)
			(size 0 0)
			(layers "F.Cu" "F.Mask" "F.Paste")
			(net "USB_HUB_PSELF")
		)
	)
	(footprint ""
		(layer "F.Cu")
		(at 527.948906 -147.965414 -90)
		(property "Reference" "X7"
			(at -1.890776 3.496818 0)
			(unlocked yes)
			(layer "F.SilkS")
			(effects
				(font
					(size 0.7874 0.5842)
					(thickness 0.1524)
				)
				(justify left)
			)
		)
		(property "Value" ""
			(at 0 0 270)
			(layer "F.Fab")
			(effects
				(font
					(size 1.27 1.27)
				)
			)
		)
		(property "Device Type" "TP_TDR_4P_FTS_TH-TP_TDR_4P_DIP,EMPTY,TP15"
			(at 1.30175 1.27 0)
			(unlocked yes)
			(layer "F.Fab")
			(hide yes)
			(effects
				(font
					(size 0.635 0.4064)
					(thickness 0.1524)
				)
			)
		)
		(property "User Part Number" "N_A"
			(at 1.30175 1.27 0)
			(unlocked yes)
			(layer "Cmts.User")
			(hide yes)
			(effects
				(font
					(size 0.635 0.4064)
					(thickness 0.1524)
				)
			)
		)
		(duplicate_pad_numbers_are_jumpers no)
		(fp_line
			(start 0 3.81)
			(end 2.54 3.81)
			(stroke
				(width 0.1524)
				(type default)
			)
			(layer "F.SilkS")
		)
		(fp_line
			(start 2.54 3.81)
			(end 2.54 3.6703)
			(stroke
				(width 0.1524)
				(type default)
			)
			(layer "F.SilkS")
		)
		(fp_line
			(start 0 3.175)
			(end 0 3.81)
			(stroke
				(width 0.1524)
				(type default)
			)
			(layer "F.SilkS")
		)
		(fp_line
			(start 2.54 1.4097)
			(end 2.54 1.1303)
			(stroke
				(width 0.1524)
				(type default)
			)
			(layer "F.SilkS")
		)
		(fp_line
			(start 0 0.635)
			(end 0 1.905)
			(stroke
				(width 0.1524)
				(type default)
			)
			(layer "F.SilkS")
		)
		(fp_line
			(start 2.54 -1.1303)
			(end 2.54 -1.27)
			(stroke
				(width 0.1524)
				(type default)
			)
			(layer "F.SilkS")
		)
		(fp_line
			(start 0 -1.27)
			(end 0 -0.635)
			(stroke
				(width 0.1524)
				(type default)
			)
			(layer "F.SilkS")
		)
		(fp_line
			(start 2.54 -1.27)
			(end 0 -1.27)
			(stroke
				(width 0.1524)
				(type default)
			)
			(layer "F.SilkS")
		)
		(fp_poly
			(pts
				(xy -0.761746 0) (xy -2.285746 0.762) (xy -2.285746 -0.762)
			)
			(stroke
				(width 0)
				(type default)
			)
			(fill yes)
			(layer "F.SilkS")
		)
		(fp_line
			(start 0 3.81)
			(end 2.54 3.81)
			(stroke
				(width 0.1)
				(type default)
			)
			(layer "F.Fab")
		)
		(fp_line
			(start 2.54 3.81)
			(end 2.54 -1.27)
			(stroke
				(width 0.1)
				(type default)
			)
			(layer "F.Fab")
		)
		(fp_line
			(start 0 -1.27)
			(end 0 3.81)
			(stroke
				(width 0.1)
				(type default)
			)
			(layer "F.Fab")
		)
		(fp_line
			(start 2.54 -1.27)
			(end 0 -1.27)
			(stroke
				(width 0.1)
				(type default)
			)
			(layer "F.Fab")
		)
		(fp_poly
			(pts
				(xy -0.761746 0) (xy -2.285746 -0.762) (xy -2.285746 0.762)
			)
			(stroke
				(width 0)
				(type default)
			)
			(fill yes)
			(layer "F.Fab")
		)
		(pad "1" thru_hole circle
			(at 0 0 270)
			(size 1.0033 1.0033)
			(drill 0.249936)
			(layers "*.Cu" "*.Mask")
			(remove_unused_layers no)
			(net "TDR_DIFF_80_TOP_DN")
			(clearance 0.10795)
			(thermal_gap 0.10795)
			(padstack
				(mode front_inner_back)
				(layer "Inner"
					(shape circle)
					(size 0.8001 0.8001)
					(clearance 0.1524)
				)
				(layer "B.Cu"
					(shape circle)
					(size 1.0033 1.0033)
					(clearance 0.10795)
				)
			)
		)
		(pad "2" thru_hole circle
			(at 2.54 0 270)
			(size 1.9939 1.9939)
			(drill 0.249936)
			(layers "*.Cu" "*.Mask")
			(remove_unused_layers no)
			(net "T1_GND")
			(clearance 0.10795)
			(thermal_gap 0.10795)
			(padstack
				(mode front_inner_back)
				(layer "Inner"
					(shape circle)
					(size 0.8001 0.8001)
					(clearance 0.1524)
				)
				(layer "B.Cu"
					(shape circle)
					(size 1.9939 1.9939)
					(clearance 0.10795)
				)
			)
		)
		(pad "3" thru_hole circle
			(at 2.54 2.54 270)
			(size 1.9939 1.9939)
			(drill 0.249936)
			(layers "*.Cu" "*.Mask")
			(remove_unused_layers no)
			(net "T1_GND")
			(clearance 0.10795)
			(thermal_gap 0.10795)
			(padstack
				(mode front_inner_back)
				(layer "Inner"
					(shape circle)
					(size 0.8001 0.8001)
					(clearance 0.1524)
				)
				(layer "B.Cu"
					(shape circle)
					(size 1.9939 1.9939)
					(clearance 0.10795)
				)
			)
		)
		(pad "4" thru_hole circle
			(at 0 2.54 270)
			(size 1.0033 1.0033)
			(drill 0.249936)
			(layers "*.Cu" "*.Mask")
			(remove_unused_layers no)
			(net "TDR_DIFF_80_TOP_DP")
			(clearance 0.10795)
			(thermal_gap 0.10795)
			(padstack
				(mode front_inner_back)
				(layer "Inner"
					(shape circle)
					(size 0.8001 0.8001)
					(clearance 0.1524)
				)
				(layer "B.Cu"
					(shape circle)
					(size 1.0033 1.0033)
					(clearance 0.10795)
				)
			)
		)
	)
	(footprint ""
		(layer "F.Cu")
		(at 144.74063 -101.894132)
		(property "Reference" "U259"
			(at 2.9464 -1.69037 0)
			(unlocked yes)
			(layer "F.SilkS")
			(effects
				(font
					(size 0.7874 0.5842)
					(thickness 0.1524)
				)
			)
		)
		(property "Value" ""
			(at 0 0 0)
			(layer "F.Fab")
			(effects
				(font
					(size 1.27 1.27)
				)
			)
		)
		(duplicate_pad_numbers_are_jumpers no)
		(fp_line
			(start -1.7272 1.1176)
			(end -1.7272 -1.1176)
			(stroke
				(width 0.1524)
				(type default)
			)
			(layer "F.SilkS")
		)
		(fp_line
			(start -0.254 -1.1176)
			(end -1.7272 -1.1176)
			(stroke
				(width 0.1524)
				(type default)
			)
			(layer "F.SilkS")
		)
		(fp_line
			(start 0 -0.7366)
			(end -0.254 -1.1176)
			(stroke
				(width 0.1524)
				(type default)
			)
			(layer "F.SilkS")
		)
		(fp_line
			(start 0.254 -1.1176)
			(end 0 -0.7366)
			(stroke
				(width 0.1524)
				(type default)
			)
			(layer "F.SilkS")
		)
		(fp_line
			(start 1.7272 -1.1176)
			(end 0.254 -1.1176)
			(stroke
				(width 0.1524)
				(type default)
			)
			(layer "F.SilkS")
		)
		(fp_line
			(start 1.7272 -1.1176)
			(end 1.7272 1.1176)
			(stroke
				(width 0.1524)
				(type default)
			)
			(layer "F.SilkS")
		)
		(fp_line
			(start 1.7272 1.1176)
			(end -1.7272 1.1176)
			(stroke
				(width 0.1524)
				(type default)
			)
			(layer "F.SilkS")
		)
		(fp_poly
			(pts
				(xy -2.7178 -1.030986) (xy -1.9558 -0.649986) (xy -2.7178 -0.268986)
			)
			(stroke
				(width 0)
				(type default)
			)
			(fill yes)
			(layer "F.SilkS")
		)
		(fp_line
			(start -1.5748 -1.1176)
			(end -1.5748 1.1176)
			(stroke
				(width 0.1)
				(type default)
			)
			(layer "F.Fab")
		)
		(fp_line
			(start -1.5748 1.1176)
			(end 1.5748 1.1176)
			(stroke
				(width 0.1)
				(type default)
			)
			(layer "F.Fab")
		)
		(fp_line
			(start 1.5748 -1.1176)
			(end -1.5748 -1.1176)
			(stroke
				(width 0.1)
				(type default)
			)
			(layer "F.Fab")
		)
		(fp_line
			(start 1.5748 1.1176)
			(end 1.5748 -1.1176)
			(stroke
				(width 0.1)
				(type default)
			)
			(layer "F.Fab")
		)
		(fp_poly
			(pts
				(xy -1.9558 -0.649986) (xy -2.7178 -0.268986) (xy -2.7178 -1.030986)
			)
			(stroke
				(width 0)
				(type default)
			)
			(fill yes)
			(layer "F.Fab")
		)
		(pad "1" smd rect
			(at -0.999998 -0.649986 270)
			(size 0.3556 1.1176)
			(layers "F.Cu" "F.Mask" "F.Paste")
			(net "M2_SSD0_CLKREQ_EN_N")
		)
		(pad "2" smd rect
			(at -0.999998 0 270)
			(size 0.3556 1.1176)
			(layers "F.Cu" "F.Mask" "F.Paste")
			(net "GND")
		)
		(pad "3" smd rect
			(at -0.999998 0.649986 270)
			(size 0.3556 1.1176)
			(layers "F.Cu" "F.Mask" "F.Paste")
			(net "RST_PERST_M2_0_N")
		)
		(pad "4" smd rect
			(at 0.999998 0.649986 270)
			(size 0.3556 1.1176)
			(layers "F.Cu" "F.Mask" "F.Paste")
			(net "RST_PERST_BUF_M2_0_N")
		)
		(pad "5" smd rect
			(at 0.999998 0 270)
			(size 0.3556 1.1176)
			(layers "F.Cu" "F.Mask" "F.Paste")
			(net "P3V3_AUX")
		)
		(pad "6" smd rect
			(at 0.999998 -0.649986 270)
			(size 0.3556 1.1176)
			(layers "F.Cu" "F.Mask" "F.Paste")
			(net "HDD_ACTIVITY_BUF")
		)
	)
	(footprint ""
		(layer "F.Cu")
		(at 78.882494 -325.661274)
		(property "Reference" "PL41"
			(at -0.829056 -16.776446 0)
			(unlocked yes)
			(layer "F.SilkS")
			(effects
				(font
					(size 0.7874 0.5842)
					(thickness 0.1524)
				)
				(justify left)
			)
		)
		(property "Value" ""
			(at 0 0 0)
			(layer "F.Fab")
			(effects
				(font
					(size 1.27 1.27)
				)
			)
		)
		(duplicate_pad_numbers_are_jumpers no)
		(fp_line
			(start -3.750056 -5.500116)
			(end -2.393442 -5.500116)
			(stroke
				(width 0.1524)
				(type default)
			)
			(layer "F.SilkS")
		)
		(fp_line
			(start -3.750056 5.500116)
			(end -3.750056 -5.500116)
			(stroke
				(width 0.1524)
				(type default)
			)
			(layer "F.SilkS")
		)
		(fp_line
			(start -2.393442 5.500116)
			(end -3.750056 5.500116)
			(stroke
				(width 0.1524)
				(type default)
			)
			(layer "F.SilkS")
		)
		(fp_line
			(start 2.393442 5.500116)
			(end 3.750056 5.500116)
			(stroke
				(width 0.1524)
				(type default)
			)
			(layer "F.SilkS")
		)
		(fp_line
			(start 3.750056 -5.500116)
			(end 2.393442 -5.500116)
			(stroke
				(width 0.1524)
				(type default)
			)
			(layer "F.SilkS")
		)
		(fp_line
			(start 3.750056 5.500116)
			(end 3.750056 -5.500116)
			(stroke
				(width 0.1524)
				(type default)
			)
			(layer "F.SilkS")
		)
		(fp_poly
			(pts
				(xy -3.9116 -4.249928) (xy -4.3434 -4.034028) (xy -4.3434 -4.465828)
			)
			(stroke
				(width 0)
				(type default)
			)
			(fill yes)
			(layer "F.SilkS")
		)
		(fp_line
			(start -3.750056 -5.500116)
			(end -3.750056 5.500116)
			(stroke
				(width 0.1)
				(type default)
			)
			(layer "F.Fab")
		)
		(fp_line
			(start -3.750056 5.500116)
			(end 3.750056 5.500116)
			(stroke
				(width 0.1)
				(type default)
			)
			(layer "F.Fab")
		)
		(fp_line
			(start 3.750056 -5.500116)
			(end -3.750056 -5.500116)
			(stroke
				(width 0.1)
				(type default)
			)
			(layer "F.Fab")
		)
		(fp_line
			(start 3.750056 5.500116)
			(end 3.750056 -5.500116)
			(stroke
				(width 0.1)
				(type default)
			)
			(layer "F.Fab")
		)
		(fp_poly
			(pts
				(xy -4.9276 -4.757928) (xy -4.9276 -3.741928) (xy -3.9116 -4.249928)
			)
			(stroke
				(width 0)
				(type default)
			)
			(fill yes)
			(layer "F.Fab")
		)
		(pad "1" smd rect
			(at 0 -4.249928 270)
			(size 2.413 4.5212)
			(layers "F.Cu" "F.Mask" "F.Paste")
			(net "SW_PVDDCR_CPU1_P1_SW2")
		)
		(pad "2" smd rect
			(at 0 -1.175004 270)
			(size 1.3716 4.5212)
			(layers "F.Cu" "F.Mask" "F.Paste")
			(net "IND_CPU1_P1_CPL1")
		)
		(pad "3" smd rect
			(at 0 1.175004 270)
			(size 1.3716 4.5212)
			(layers "F.Cu" "F.Mask" "F.Paste")
			(net "IND_CPU1_P1_CPL2")
		)
		(pad "4" smd rect
			(at 0 4.249928 270)
			(size 2.413 4.5212)
			(layers "F.Cu" "F.Mask" "F.Paste")
			(net "PVDDCR_CPU1_P1")
		)
	)
)
